(kicad_pcb
	(version 20221018)
	(generator pcbnew)
	(general
    (thickness 1.7403)
  )
	(paper "A4")
	(title_block
    (title "Data Center RDIMM DDR4 Tester")
    (date "2024-09-30")
    (rev "1.2.4")
		(comment 9 "footprints 129-132 of 690")
	)
	(layers
    (0 "F.Cu" signal)
    (1 "In1.Cu" power)
    (2 "In2.Cu" signal)
    (3 "In3.Cu" power)
    (4 "In4.Cu" power)
    (5 "In5.Cu" signal)
    (6 "In6.Cu" power)
    (7 "In7.Cu" signal)
    (8 "In8.Cu" power)
    (9 "In9.Cu" signal)
    (10 "In10.Cu" power)
    (31 "B.Cu" signal)
    (32 "B.Adhes" user "B.Adhesive")
    (33 "F.Adhes" user "F.Adhesive")
    (34 "B.Paste" user)
    (35 "F.Paste" user)
    (36 "B.SilkS" user "B.Silkscreen")
    (37 "F.SilkS" user "F.Silkscreen")
    (38 "B.Mask" user)
    (39 "F.Mask" user)
    (40 "Dwgs.User" user "User.Drawings")
    (41 "Cmts.User" user "User.Comments")
    (42 "Eco1.User" user "User.Eco1")
    (43 "Eco2.User" user "User.Eco2")
    (44 "Edge.Cuts" user)
    (45 "Margin" user)
    (46 "B.CrtYd" user "B.Courtyard")
    (47 "F.CrtYd" user "F.Courtyard")
    (48 "B.Fab" user)
    (49 "F.Fab" user)
  )
	(footprint "data-center-rdimm-ddr4-tester-footprints:R-PDSO-N15" locked (layer "F.Cu")
    (at 211.3985 119.655 -90)
    (property "Author" "Antmicro")
    (property "License" "Apache-2.0")
    (property "MPN" "TPD8S009DSMR")
    (property "Manufacturer" "Texas Instruments")
    (property "Sheetfile" "interfaces.kicad_sch")
    (property "Sheetname" "Interfaces")
    (attr smd)
    (fp_text reference "IC3" (at 2.665 -3.5015 180) (layer "F.SilkS")
        (effects (font (size 0.7 0.7) (thickness 0.15)) (justify right bottom))
    )
    (fp_text value "TPD8S009DSMR" (at 0 4.4 90) (layer "F.Fab") hide
        (effects (font (size 0.7 0.7) (thickness 0.15)) (justify right bottom))
    )
    (fp_text user "${REFERENCE}" (at -4.1 4.95 90) (layer "F.Fab") hide
        (effects (font (size 0.7 0.7) (thickness 0.15)) (justify right bottom))
    )
    (fp_text user "Author: Antmicro" (at -4.1 7.35 90) (layer "F.Fab") hide
        (effects (font (size 0.7 0.7) (thickness 0.15)) (justify right bottom))
    )
    (fp_text user "License: Apache-2.0" (at -4.1 6.15 90) (layer "F.Fab") hide
        (effects (font (size 0.7 0.7) (thickness 0.15)) (justify right bottom))
    )
    (fp_circle (center -1.6 -3.2) (end -1.6 -3.15)
      (stroke (width 0.15) (type solid)) (fill solid) (layer "F.SilkS"))
    (fp_rect (start 1.8 -3.5) (end -1.89 3.49)
      (stroke (width 0.05) (type solid)) (fill none) (layer "F.CrtYd"))
    (fp_line (start -1.3 -3.051) (end -1.1 -3.25)
      (stroke (width 0.15) (type solid)) (layer "F.Fab"))
    (fp_rect (start 1.301 -3.25) (end -1.3 3.249)
      (stroke (width 0.15) (type solid)) (fill none) (layer "F.Fab"))
    (pad "1" smd roundrect locked (at -0.95 -2.75 180) (size 0.3 1.45) (layers "F.Cu" "F.Paste" "F.Mask") (roundrect_rratio 0.25)
      (net 48 "C_TMDS_D2_P") (pinfunction "D0+") (pintype "passive"))
    (pad "2" smd roundrect locked (at -0.95 -2.25 180) (size 0.3 1.45) (layers "F.Cu" "F.Paste" "F.Mask") (roundrect_rratio 0.25)
      (net 9 "GND") (pinfunction "GND") (pintype "passive"))
    (pad "3" smd roundrect locked (at -0.95 -1.75 180) (size 0.3 1.45) (layers "F.Cu" "F.Paste" "F.Mask") (roundrect_rratio 0.25)
      (net 47 "C_TMDS_D2_N") (pinfunction "D0-") (pintype "passive"))
    (pad "4" smd roundrect locked (at -0.95 -1.25 180) (size 0.3 1.45) (layers "F.Cu" "F.Paste" "F.Mask") (roundrect_rratio 0.25)
      (net 46 "C_TMDS_D1_P") (pinfunction "D1+") (pintype "passive"))
    (pad "5" smd roundrect locked (at -0.95 -0.75 180) (size 0.3 1.45) (layers "F.Cu" "F.Paste" "F.Mask") (roundrect_rratio 0.25)
      (net 9 "GND") (pinfunction "GND") (pintype "passive"))
    (pad "6" smd roundrect locked (at -0.95 -0.25 180) (size 0.3 1.45) (layers "F.Cu" "F.Paste" "F.Mask") (roundrect_rratio 0.25)
      (net 54 "C_TMDS_D1_N") (pinfunction "D1-") (pintype "passive"))
    (pad "7" smd roundrect locked (at -0.95 0.247 180) (size 0.3 1.45) (layers "F.Cu" "F.Paste" "F.Mask") (roundrect_rratio 0.25)
      (net 45 "C_TMDS_D0_P") (pinfunction "D2+") (pintype "passive"))
    (pad "8" smd roundrect locked (at -0.95 0.747 180) (size 0.3 1.45) (layers "F.Cu" "F.Paste" "F.Mask") (roundrect_rratio 0.25)
      (net 9 "GND") (pinfunction "GND") (pintype "passive"))
    (pad "9" smd roundrect locked (at -0.95 1.249 180) (size 0.3 1.45) (layers "F.Cu" "F.Paste" "F.Mask") (roundrect_rratio 0.25)
      (net 44 "C_TMDS_D0_N") (pinfunction "D2-") (pintype "passive"))
    (pad "10" smd roundrect locked (at -0.95 1.749 180) (size 0.3 1.45) (layers "F.Cu" "F.Paste" "F.Mask") (roundrect_rratio 0.25)
      (net 42 "C_TMDS_CLK_P") (pinfunction "D3+") (pintype "passive"))
    (pad "11" smd roundrect locked (at -0.95 2.249 180) (size 0.3 1.45) (layers "F.Cu" "F.Paste" "F.Mask") (roundrect_rratio 0.25)
      (net 9 "GND") (pinfunction "GND") (pintype "passive"))
    (pad "12" smd roundrect locked (at -0.95 2.749 180) (size 0.3 1.45) (layers "F.Cu" "F.Paste" "F.Mask") (roundrect_rratio 0.25)
      (net 43 "C_TMDS_CLK_N") (pinfunction "D3-") (pintype "passive"))
    (pad "13" smd roundrect locked (at 0.901 1.499 180) (size 0.3 1.45) (layers "F.Cu" "F.Paste" "F.Mask") (roundrect_rratio 0.25)
      (net 143 "3V3_SYS") (pinfunction "VCC") (pintype "power_in"))
    (pad "14" smd roundrect locked (at 0.901 0 180) (size 0.3 1.45) (layers "F.Cu" "F.Paste" "F.Mask") (roundrect_rratio 0.25)
      (net 111 "unconnected-(IC3-NC-Pad14)") (pinfunction "NC") (pintype "no_connect"))
    (pad "15" smd roundrect locked (at 0.901 -1.5 180) (size 0.3 1.45) (layers "F.Cu" "F.Paste" "F.Mask") (roundrect_rratio 0.25)
      (net 143 "3V3_SYS") (pinfunction "VCC") (pintype "passive"))
  )
	(footprint "data-center-rdimm-ddr4-tester-footprints:HDMI-A_Receptacle_WE_685119134923" locked (layer "F.Cu")
    (at 209.625 132.18 180)
    (property "Author" "Antmicro")
    (property "License" "Apache-2.0")
    (property "MPN" "685119134923")
    (property "Manufacturer" "Würth Elektronik")
    (property "Sheetfile" "interfaces.kicad_sch")
    (property "Sheetname" "Interfaces")
    (property "ki_description" "HDMI Receptacle Connector 19 Position Surface Mount, Right Angle; Through Hole")
    (property "ki_keywords" "HDMI, CONNECTOR, THT")
    (attr smd)
    (fp_text reference "J6" (at -6.275 7.72 180) (layer "F.SilkS")
        (effects (font (size 0.7 0.7) (thickness 0.15)) (justify left bottom))
    )
    (fp_text value "HDMI_A_Female_685119134923" (at 0 7.8 180) (layer "F.Fab")
        (effects (font (size 0.7 0.7) (thickness 0.15)) (justify left bottom))
    )
    (fp_text user "${REFERENCE}" (at -8 9.5 180) (layer "F.Fab") hide
        (effects (font (size 0.7 0.7) (thickness 0.15)) (justify left bottom))
    )
    (fp_text user "Author: Antmicro" (at -8 11 180) (layer "F.Fab") hide
        (effects (font (size 0.7 0.7) (thickness 0.15)) (justify left bottom))
    )
    (fp_text user "License: Apache-2.0" (at -8 12.5 180) (layer "F.Fab") hide
        (effects (font (size 0.7 0.7) (thickness 0.15)) (justify left bottom))
    )
    (fp_line (start -7.55 -0.125) (end -7.55 2.65)
      (stroke (width 0.12) (type solid)) (layer "F.SilkS"))
    (fp_line (start -4.85 5.65) (end -5.8 5.65)
      (stroke (width 0.12) (type solid)) (layer "F.SilkS"))
    (fp_line (start 5.7 5.65) (end 4.75 5.65)
      (stroke (width 0.12) (type solid)) (layer "F.SilkS"))
    (fp_line (start 7.55 2.75) (end 7.55 -0.15)
      (stroke (width 0.12) (type solid)) (layer "F.SilkS"))
    (fp_circle (center -4.9 5.9) (end -4.85 5.9)
      (stroke (width 0.15) (type solid)) (fill none) (layer "F.SilkS"))
    (fp_rect (start -8.05 -6.32) (end 7.949 6.78)
      (stroke (width 0.05) (type solid)) (fill none) (layer "F.CrtYd"))
    (fp_line (start -7.05 -5.616) (end 6.95 -5.616)
      (stroke (width 0.15) (type solid)) (layer "F.Fab"))
    (fp_line (start -7.05 5.525) (end -7.05 -5.616)
      (stroke (width 0.15) (type solid)) (layer "F.Fab"))
    (fp_line (start -7.05 5.525) (end -6.05 6.525)
      (stroke (width 0.15) (type solid)) (layer "F.Fab"))
    (fp_line (start 6.95 6.535) (end -6.05 6.535)
      (stroke (width 0.15) (type solid)) (layer "F.Fab"))
    (fp_line (start 6.95 6.535) (end 6.95 -5.616)
      (stroke (width 0.15) (type solid)) (layer "F.Fab"))
    (pad "1" smd rect locked (at -4.55 5.224 180) (size 0.28 2.6) (layers "F.Cu" "F.Paste" "F.Mask")
      (net 48 "C_TMDS_D2_P") (pinfunction "D2+") (pintype "bidirectional"))
    (pad "2" smd rect locked (at -4.05 5.224 180) (size 0.28 2.6) (layers "F.Cu" "F.Paste" "F.Mask")
      (net 9 "GND") (pinfunction "D2S") (pintype "passive"))
    (pad "3" smd rect locked (at -3.551 5.224 180) (size 0.28 2.6) (layers "F.Cu" "F.Paste" "F.Mask")
      (net 47 "C_TMDS_D2_N") (pinfunction "D2-") (pintype "bidirectional"))
    (pad "4" smd rect locked (at -3.051 5.224 180) (size 0.28 2.6) (layers "F.Cu" "F.Paste" "F.Mask")
      (net 46 "C_TMDS_D1_P") (pinfunction "D1+") (pintype "bidirectional"))
    (pad "5" smd rect locked (at -2.551 5.224 180) (size 0.28 2.6) (layers "F.Cu" "F.Paste" "F.Mask")
      (net 9 "GND") (pinfunction "D1S") (pintype "passive"))
    (pad "6" smd rect locked (at -2.05 5.224 180) (size 0.28 2.6) (layers "F.Cu" "F.Paste" "F.Mask")
      (net 54 "C_TMDS_D1_N") (pinfunction "D1-") (pintype "bidirectional"))
    (pad "7" smd rect locked (at -1.551 5.224 180) (size 0.28 2.6) (layers "F.Cu" "F.Paste" "F.Mask")
      (net 45 "C_TMDS_D0_P") (pinfunction "D0+") (pintype "bidirectional"))
    (pad "8" smd rect locked (at -1.051 5.224 180) (size 0.28 2.6) (layers "F.Cu" "F.Paste" "F.Mask")
      (net 9 "GND") (pinfunction "D0S") (pintype "passive"))
    (pad "9" smd rect locked (at -0.551 5.224 180) (size 0.28 2.6) (layers "F.Cu" "F.Paste" "F.Mask")
      (net 44 "C_TMDS_D0_N") (pinfunction "D0-") (pintype "bidirectional"))
    (pad "10" smd rect locked (at -0.051 5.224 180) (size 0.28 2.6) (layers "F.Cu" "F.Paste" "F.Mask")
      (net 42 "C_TMDS_CLK_P") (pinfunction "CK+") (pintype "bidirectional"))
    (pad "11" smd rect locked (at 0.45 5.224 180) (size 0.28 2.6) (layers "F.Cu" "F.Paste" "F.Mask")
      (net 9 "GND") (pinfunction "CKS") (pintype "passive"))
    (pad "12" smd rect locked (at 0.95 5.224 180) (size 0.28 2.6) (layers "F.Cu" "F.Paste" "F.Mask")
      (net 43 "C_TMDS_CLK_N") (pinfunction "CK-") (pintype "bidirectional"))
    (pad "13" smd rect locked (at 1.449 5.224 180) (size 0.28 2.6) (layers "F.Cu" "F.Paste" "F.Mask")
      (net 556 "Net-(J6-CEC)") (pinfunction "CEC") (pintype "bidirectional"))
    (pad "14" smd rect locked (at 1.949 5.224 180) (size 0.28 2.6) (layers "F.Cu" "F.Paste" "F.Mask")
      (net 557 "unconnected-(J6-UTILITY{slash}HEAC+-Pad14)") (pinfunction "UTILITY/HEAC+") (pintype "bidirectional+no_connect"))
    (pad "15" smd rect locked (at 2.45 5.224 180) (size 0.28 2.6) (layers "F.Cu" "F.Paste" "F.Mask")
      (net 560 "Net-(J6-SCL)") (pinfunction "SCL") (pintype "bidirectional"))
    (pad "16" smd rect locked (at 2.95 5.224 180) (size 0.28 2.6) (layers "F.Cu" "F.Paste" "F.Mask")
      (net 561 "Net-(J6-SDA)") (pinfunction "SDA") (pintype "bidirectional"))
    (pad "17" smd rect locked (at 3.45 5.224 180) (size 0.28 2.6) (layers "F.Cu" "F.Paste" "F.Mask")
      (net 9 "GND") (pinfunction "GND") (pintype "power_in"))
    (pad "18" smd rect locked (at 3.95 5.224 180) (size 0.28 2.6) (layers "F.Cu" "F.Paste" "F.Mask")
      (net 562 "Net-(J6-+5V)") (pinfunction "+5V") (pintype "power_in"))
    (pad "19" smd rect locked (at 4.45 5.224 180) (size 0.28 2.6) (layers "F.Cu" "F.Paste" "F.Mask")
      (net 563 "Net-(J6-HPD{slash}HEAC-)") (pinfunction "HPD/HEAC-") (pintype "bidirectional"))
    (pad "SH" thru_hole oval locked (at -7.3 -1.577 180) (size 1.5 2.7) (drill oval 0.9 2.1) (layers "*.Cu" "*.Mask")
      (net 863 "GND1") (pinfunction "SH") (pintype "passive"))
    (pad "SH" thru_hole oval locked (at -7.3 4.424 180) (size 1.5 3.3) (drill oval 0.9 2.7) (layers "*.Cu" "*.Mask")
      (net 863 "GND1") (pinfunction "SH") (pintype "passive"))
    (pad "SH" thru_hole oval locked (at 7.2 -1.577 180) (size 1.5 2.7) (drill oval 0.9 2.1) (layers "*.Cu" "*.Mask")
      (net 863 "GND1") (pinfunction "SH") (pintype "passive"))
    (pad "SH" thru_hole oval locked (at 7.2 4.424 180) (size 1.5 3.3) (drill oval 0.9 2.7) (layers "*.Cu" "*.Mask")
      (net 863 "GND1") (pinfunction "SH") (pintype "passive"))
  )
	(footprint "data-center-rdimm-ddr4-tester-footprints:SW_B3U-1000P_SMD" (layer "F.Cu")
    (at 222.225 82.975 180)
    (property "Author" "Antmicro")
    (property "License" "Apache-2.0")
    (property "MPN" "B3U-1000P")
    (property "Manufacturer" "Omron")
    (property "Sheetfile" "config-spi.kicad_sch")
    (property "Sheetname" "Config SPI flash")
    (property "ki_description" "Tactile Switch, B3U, Top Actuated, Surface Mount, Round Button, 153 gf, 50mA at 12VDC")
    (property "ki_keywords" "VERTICAL, SMT, SWITCH, MECHANICAL, TACTILE")
    (attr smd)
    (fp_text reference "PROG_B1" (at 2.385 -2.575 180) (layer "F.SilkS")
        (effects (font (size 0.7 0.7) (thickness 0.15)) (justify left bottom))
    )
    (fp_text value "SW_B3U-1000P" (at 0 2.5) (layer "F.Fab")
        (effects (font (size 0.7 0.7) (thickness 0.15)) (justify right bottom))
    )
    (fp_text user "Author: Antmicro" (at -2.249 5.7) (layer "F.Fab") hide
        (effects (font (size 0.7 0.7) (thickness 0.15)) (justify right bottom))
    )
    (fp_text user "${REFERENCE}" (at -2.249 4.5) (layer "F.Fab") hide
        (effects (font (size 0.7 0.7) (thickness 0.15)) (justify right bottom))
    )
    (fp_text user "License: Apache-2.0" (at -2.249 6.9) (layer "F.Fab") hide
        (effects (font (size 0.7 0.7) (thickness 0.15)) (justify right bottom))
    )
    (fp_line (start -1.601 -0.95) (end -2 -0.95)
      (stroke (width 0.15) (type solid)) (layer "F.SilkS"))
    (fp_line (start -1.6 -1.4) (end -1.601 -0.95)
      (stroke (width 0.15) (type solid)) (layer "F.SilkS"))
    (fp_line (start -1.6 -1.4) (end -1.1 -1.4)
      (stroke (width 0.15) (type solid)) (layer "F.SilkS"))
    (fp_line (start -1.6 1.4) (end -1.6 0.95)
      (stroke (width 0.15) (type solid)) (layer "F.SilkS"))
    (fp_line (start -1.6 1.4) (end -1.1 1.4)
      (stroke (width 0.15) (type solid)) (layer "F.SilkS"))
    (fp_line (start 1.6 -1.4) (end 1.1 -1.4)
      (stroke (width 0.15) (type solid)) (layer "F.SilkS"))
    (fp_line (start 1.6 -1.4) (end 1.6 -0.95)
      (stroke (width 0.15) (type solid)) (layer "F.SilkS"))
    (fp_line (start 1.6 1.4) (end 1.1 1.4)
      (stroke (width 0.15) (type solid)) (layer "F.SilkS"))
    (fp_line (start 1.6 1.4) (end 1.6 0.95)
      (stroke (width 0.15) (type solid)) (layer "F.SilkS"))
    (fp_rect (start -2.249 -1.55) (end 2.25 1.549)
      (stroke (width 0.05) (type solid)) (fill none) (layer "F.CrtYd"))
    (fp_rect (start -1.5 -1.29) (end 1.499 1.289)
      (stroke (width 0.15) (type solid)) (fill none) (layer "F.Fab"))
    (pad "1" smd rect (at -1.7 0 180) (size 0.8 1.7) (layers "F.Cu" "F.Paste" "F.Mask")
      (net 91 "PROGRAM_B") (pinfunction "1") (pintype "passive"))
    (pad "2" smd rect (at 1.699 0 180) (size 0.8 1.7) (layers "F.Cu" "F.Paste" "F.Mask")
      (net 9 "GND") (pinfunction "2") (pintype "passive"))
  )
	(footprint "data-center-rdimm-ddr4-tester-footprints:LED_0603_1608Metric_G" (layer "F.Cu")
    (at 251.7 107 180)
    (descr "LED SMD 0603 Green")
    (tags "LED SMD 0603 Green")
    (property "Author" "Antmicro")
    (property "License" "Apache-2.0")
    (property "MPN" "KP-1608CGCK")
    (property "Manufacturer" "Kingbright")
    (property "Sheetfile" "interfaces.kicad_sch")
    (property "Sheetname" "Interfaces")
    (attr smd)
    (fp_text reference "D5" (at 0.84 -1.33 180) (layer "F.SilkS")
        (effects (font (size 0.7 0.7) (thickness 0.15)) (justify left bottom))
    )
    (fp_text value "LED_G_0603_KP-1608CGCK" (at 0 1.6 180) (layer "F.Fab") hide
        (effects (font (size 0.7 0.7) (thickness 0.15)) (justify left bottom))
    )
    (fp_text user "${REFERENCE}" (at -1.31 3.769 180) (layer "F.Fab") hide
        (effects (font (size 0.7 0.7) (thickness 0.15)) (justify left bottom))
    )
    (fp_text user "Author: Antmicro" (at -1.31 4.769 180) (layer "F.Fab") hide
        (effects (font (size 0.7 0.7) (thickness 0.15)) (justify left bottom))
    )
    (fp_text user "License: Apache-2.0" (at -1.31 5.769 180) (layer "F.Fab") hide
        (effects (font (size 0.7 0.7) (thickness 0.15)) (justify left bottom))
    )
    (fp_line (start -0.27 -0.35) (end 0.27 -0.35)
      (stroke (width 0.15) (type solid)) (layer "F.SilkS"))
    (fp_line (start -0.27 0.351) (end 0.27 0.351)
      (stroke (width 0.15) (type solid)) (layer "F.SilkS"))
    (fp_line (start -0.106328 -0.200008) (end -0.106328 0.199992)
      (stroke (width 0.1) (type solid)) (layer "F.SilkS"))
    (fp_line (start -0.106328 -0.200008) (end 0.093672 -0.000008)
      (stroke (width 0.1) (type solid)) (layer "F.SilkS"))
    (fp_line (start -0.106328 -0.000008) (end -0.29 0)
      (stroke (width 0.1) (type solid)) (layer "F.SilkS"))
    (fp_line (start 0.093672 -0.200008) (end 0.093672 0.199992)
      (stroke (width 0.1) (type solid)) (layer "F.SilkS"))
    (fp_line (start 0.093672 -0.000008) (end -0.106328 0.199992)
      (stroke (width 0.1) (type solid)) (layer "F.SilkS"))
    (fp_line (start 0.093672 -0.000008) (end 0.293672 -0.000008)
      (stroke (width 0.1) (type solid)) (layer "F.SilkS"))
    (fp_line (start 1.25 0.32) (end 1.25 -0.32)
      (stroke (width 0.15) (type solid)) (layer "F.SilkS"))
    (fp_rect (start 1.26 0.65) (end -1.26 -0.65)
      (stroke (width 0.05) (type solid)) (fill none) (layer "F.CrtYd"))
    (fp_line (start -0.599 0) (end -0.201 0)
      (stroke (width 0.15) (type solid)) (layer "F.Fab"))
    (fp_line (start -0.201 -0.2) (end -0.201 0)
      (stroke (width 0.15) (type solid)) (layer "F.Fab"))
    (fp_line (start -0.201 0) (end -0.201 0.202)
      (stroke (width 0.15) (type solid)) (layer "F.Fab"))
    (fp_line (start -0.201 0.202) (end 0.101 0)
      (stroke (width 0.15) (type solid)) (layer "F.Fab"))
    (fp_line (start 0.101 0) (end -0.201 -0.2)
      (stroke (width 0.15) (type solid)) (layer "F.Fab"))
    (fp_line (start 0.199 -0.2) (end 0.199 -0.1)
      (stroke (width 0.15) (type solid)) (layer "F.Fab"))
    (fp_line (start 0.199 0) (end 0.597 0)
      (stroke (width 0.15) (type solid)) (layer "F.Fab"))
    (fp_line (start 0.199 0.202) (end 0.199 -0.1)
      (stroke (width 0.15) (type solid)) (layer "F.Fab"))
    (fp_rect (start -0.848 -0.4) (end 0.85 0.402)
      (stroke (width 0.15) (type solid)) (fill none) (layer "F.Fab"))
    (pad "1" smd rect (at -0.75 0) (size 0.8 0.8) (layers "F.Cu" "F.Paste" "F.Mask")
      (net 143 "3V3_SYS") (pinfunction "1") (pintype "passive"))
    (pad "2" smd rect (at 0.75 0) (size 0.8 0.8) (layers "F.Cu" "F.Paste" "F.Mask")
      (net 63 "Net-(D5-Pad2)") (pinfunction "2") (pintype "passive"))
  )
)
